(kicad_pcb
	(version 20241229)
	(generator "pcbnew")
	(generator_version "9.0")
	(general
		(thickness 1.6)
		(legacy_teardrops no)
	)
	(paper "A4")
	(title_block
		(title "GMSL Deserializer")
		(date "2025-10-09")
		(rev "1.0.4")
		(company "Antmicro Ltd")
		(comment 1 "www.antmicro.com")
		(comment 9 "footprints 154-159 of 235")
	)
	(layers
		(0 "F.Cu" signal)
		(4 "In1.Cu" power)
		(6 "In2.Cu" power)
		(2 "B.Cu" signal)
		(9 "F.Adhes" user "F.Adhesive")
		(11 "B.Adhes" user "B.Adhesive")
		(13 "F.Paste" user)
		(15 "B.Paste" user)
		(5 "F.SilkS" user "F.Silkscreen")
		(7 "B.SilkS" user "B.Silkscreen")
		(1 "F.Mask" user)
		(3 "B.Mask" user)
		(17 "Dwgs.User" user "User.Drawings")
		(19 "Cmts.User" user "User.Comments")
		(21 "Eco1.User" user "User.Eco1")
		(23 "Eco2.User" user "User.Eco2")
		(25 "Edge.Cuts" user)
		(27 "Margin" user)
		(31 "F.CrtYd" user "F.Courtyard")
		(29 "B.CrtYd" user "B.Courtyard")
		(35 "F.Fab" user)
		(33 "B.Fab" user)
	)
	(footprint "antmicro-footprints:L_Coilcraft-PFL1609"
		(layer "F.Cu")
		(at 140.18 53.594)
		(property "Reference" "L14"
			(at -1.470634 1.480804 0)
			(layer "F.SilkS")
			(effects
				(font
					(size 0.7 0.7)
					(thickness 0.15)
				)
				(justify left bottom)
			)
		)
		(property "Value" "L_470n_1A_Coilcraft-PFL1609"
			(at 0 2 0)
			(layer "F.Fab")
			(effects
				(font
					(size 0.7 0.7)
					(thickness 0.15)
				)
				(justify left bottom)
			)
		)
		(property "Datasheet" "https://www.coilcraft.com/getmedia/2f4cd442-d64d-4413-a518-12fcfd03318d/pfl1609.pdf"
			(at 0 0 0)
			(layer "F.Fab")
			(hide yes)
			(effects
				(font
					(size 1.27 1.27)
					(thickness 0.15)
				)
			)
		)
		(property "Description" "Power Inductor (SMT), 6.8 µH, 9.2 A, Shielded, 12.8 A, XAL7070"
			(at 0 0 0)
			(layer "F.Fab")
			(hide yes)
			(effects
				(font
					(size 1.27 1.27)
					(thickness 0.15)
				)
			)
		)
		(property "Author" "Antmicro"
			(at 0 0 0)
			(layer "F.Fab")
			(hide yes)
			(effects
				(font
					(size 1 1)
					(thickness 0.15)
				)
			)
		)
		(property "IMax" "1 A"
			(at 0 0 0)
			(layer "F.Fab")
			(hide yes)
			(effects
				(font
					(size 1 1)
					(thickness 0.15)
				)
			)
		)
		(property "ISat" "0.99 A"
			(at 0 0 0)
			(layer "F.Fab")
			(hide yes)
			(effects
				(font
					(size 1 1)
					(thickness 0.15)
				)
			)
		)
		(property "License" "Apache-2.0"
			(at 0 0 0)
			(layer "F.Fab")
			(hide yes)
			(effects
				(font
					(size 1 1)
					(thickness 0.15)
				)
			)
		)
		(property "MPN" "PFL1609-471"
			(at 0 0 0)
			(layer "F.Fab")
			(hide yes)
			(effects
				(font
					(size 1 1)
					(thickness 0.15)
				)
			)
		)
		(property "Manufacturer" "Coilcraft"
			(at 0 0 0)
			(layer "F.Fab")
			(hide yes)
			(effects
				(font
					(size 1 1)
					(thickness 0.15)
				)
			)
		)
		(property "Size" "1.07x1.8"
			(at 0 0 0)
			(layer "F.Fab")
			(hide yes)
			(effects
				(font
					(size 1 1)
					(thickness 0.15)
				)
			)
		)
		(property "Val" "470n/0.99A"
			(at 0 0 0)
			(layer "F.Fab")
			(hide yes)
			(effects
				(font
					(size 1 1)
					(thickness 0.15)
				)
			)
		)
		(sheetname "/Power/")
		(sheetfile "power.kicad_sch")
		(attr smd)
		(fp_line
			(start -0.23 -0.45)
			(end 0.23 -0.45)
			(stroke
				(width 0.15)
				(type solid)
			)
			(layer "F.SilkS")
		)
		(fp_line
			(start -0.23 0.45)
			(end 0.23 0.45)
			(stroke
				(width 0.15)
				(type solid)
			)
			(layer "F.SilkS")
		)
		(fp_rect
			(start -1.2 -0.84)
			(end 1.2 0.84)
			(stroke
				(width 0.05)
				(type solid)
			)
			(fill no)
			(layer "F.CrtYd")
		)
		(fp_rect
			(start -0.9 -0.535)
			(end 0.9 0.535)
			(stroke
				(width 0.15)
				(type solid)
			)
			(fill no)
			(layer "F.Fab")
		)
		(pad "1" smd roundrect
			(at -0.635 0)
			(size 0.64 1.02)
			(layers "F.Cu" "F.Mask" "F.Paste")
			(roundrect_rratio 0.15)
			(net 60 "Net-(L10-Pad2)")
			(pintype "passive")
		)
		(pad "2" smd roundrect
			(at 0.635 0)
			(size 0.64 1.02)
			(layers "F.Cu" "F.Mask" "F.Paste")
			(roundrect_rratio 0.15)
			(net 115 "/Connectors/PoCB")
			(pintype "passive")
		)
	)
	(footprint "antmicro-footprints:L_Coilcraft-PFL1609"
		(layer "F.Cu")
		(at 151.638 53.594)
		(property "Reference" "L15"
			(at -1.498634 1.480804 0)
			(layer "F.SilkS")
			(effects
				(font
					(size 0.7 0.7)
					(thickness 0.15)
				)
				(justify left bottom)
			)
		)
		(property "Value" "L_470n_1A_Coilcraft-PFL1609"
			(at 0 2 0)
			(layer "F.Fab")
			(effects
				(font
					(size 0.7 0.7)
					(thickness 0.15)
				)
				(justify left bottom)
			)
		)
		(property "Datasheet" "https://www.coilcraft.com/getmedia/2f4cd442-d64d-4413-a518-12fcfd03318d/pfl1609.pdf"
			(at 0 0 0)
			(layer "F.Fab")
			(hide yes)
			(effects
				(font
					(size 1.27 1.27)
					(thickness 0.15)
				)
			)
		)
		(property "Description" "Power Inductor (SMT), 6.8 µH, 9.2 A, Shielded, 12.8 A, XAL7070"
			(at 0 0 0)
			(layer "F.Fab")
			(hide yes)
			(effects
				(font
					(size 1.27 1.27)
					(thickness 0.15)
				)
			)
		)
		(property "Author" "Antmicro"
			(at 0 0 0)
			(layer "F.Fab")
			(hide yes)
			(effects
				(font
					(size 1 1)
					(thickness 0.15)
				)
			)
		)
		(property "IMax" "1 A"
			(at 0 0 0)
			(layer "F.Fab")
			(hide yes)
			(effects
				(font
					(size 1 1)
					(thickness 0.15)
				)
			)
		)
		(property "ISat" "0.99 A"
			(at 0 0 0)
			(layer "F.Fab")
			(hide yes)
			(effects
				(font
					(size 1 1)
					(thickness 0.15)
				)
			)
		)
		(property "License" "Apache-2.0"
			(at 0 0 0)
			(layer "F.Fab")
			(hide yes)
			(effects
				(font
					(size 1 1)
					(thickness 0.15)
				)
			)
		)
		(property "MPN" "PFL1609-471"
			(at 0 0 0)
			(layer "F.Fab")
			(hide yes)
			(effects
				(font
					(size 1 1)
					(thickness 0.15)
				)
			)
		)
		(property "Manufacturer" "Coilcraft"
			(at 0 0 0)
			(layer "F.Fab")
			(hide yes)
			(effects
				(font
					(size 1 1)
					(thickness 0.15)
				)
			)
		)
		(property "Size" "1.07x1.8"
			(at 0 0 0)
			(layer "F.Fab")
			(hide yes)
			(effects
				(font
					(size 1 1)
					(thickness 0.15)
				)
			)
		)
		(property "Val" "470n/0.99A"
			(at 0 0 0)
			(layer "F.Fab")
			(hide yes)
			(effects
				(font
					(size 1 1)
					(thickness 0.15)
				)
			)
		)
		(sheetname "/Power/")
		(sheetfile "power.kicad_sch")
		(attr smd)
		(fp_line
			(start -0.23 -0.45)
			(end 0.23 -0.45)
			(stroke
				(width 0.15)
				(type solid)
			)
			(layer "F.SilkS")
		)
		(fp_line
			(start -0.23 0.45)
			(end 0.23 0.45)
			(stroke
				(width 0.15)
				(type solid)
			)
			(layer "F.SilkS")
		)
		(fp_rect
			(start -1.2 -0.84)
			(end 1.2 0.84)
			(stroke
				(width 0.05)
				(type solid)
			)
			(fill no)
			(layer "F.CrtYd")
		)
		(fp_rect
			(start -0.9 -0.535)
			(end 0.9 0.535)
			(stroke
				(width 0.15)
				(type solid)
			)
			(fill no)
			(layer "F.Fab")
		)
		(pad "1" smd roundrect
			(at -0.635 0)
			(size 0.64 1.02)
			(layers "F.Cu" "F.Mask" "F.Paste")
			(roundrect_rratio 0.15)
			(net 61 "Net-(L11-Pad2)")
			(pintype "passive")
		)
		(pad "2" smd roundrect
			(at 0.635 0)
			(size 0.64 1.02)
			(layers "F.Cu" "F.Mask" "F.Paste")
			(roundrect_rratio 0.15)
			(net 116 "/Connectors/PoCC")
			(pintype "passive")
		)
	)
	(footprint "antmicro-footprints:R_0402_1005Metric"
		(layer "F.Cu")
		(at 152.3492 78.8416 45)
		(descr "Resistor SMD 0402")
		(tags "resistor SMD 0402")
		(property "Reference" "R48"
			(at -0.933947 2.44263 45)
			(layer "F.SilkS")
			(effects
				(font
					(size 0.7 0.7)
					(thickness 0.15)
				)
				(justify left bottom)
			)
		)
		(property "Value" "R_80k6_0402"
			(at -1.011843 1.772046 45)
			(layer "F.Fab")
			(effects
				(font
					(size 0.7 0.7)
					(thickness 0.15)
				)
				(justify left bottom)
			)
		)
		(property "Datasheet" "https://www.bourns.com/docs/product-datasheets/cr.pdf"
			(at 0 0 45)
			(layer "F.Fab")
			(hide yes)
			(effects
				(font
					(size 1.27 1.27)
					(thickness 0.15)
				)
			)
		)
		(property "Description" "SMD Chip Resistor, 80.6 kohm, ± 1%, 100 mW, 0402 [1005 Metric], Thick Film, Precision"
			(at 0 0 45)
			(layer "F.Fab")
			(hide yes)
			(effects
				(font
					(size 1.27 1.27)
					(thickness 0.15)
				)
			)
		)
		(property "Author" "Antmicro"
			(at 100.371477 -84.634982 0)
			(layer "F.Fab")
			(hide yes)
			(effects
				(font
					(size 1 1)
					(thickness 0.15)
				)
			)
		)
		(property "License" "Apache-2.0"
			(at 100.371477 -84.634982 0)
			(layer "F.Fab")
			(hide yes)
			(effects
				(font
					(size 1 1)
					(thickness 0.15)
				)
			)
		)
		(property "MPN" "CR0402-FX-8062GLF"
			(at 100.371477 -84.634982 0)
			(layer "F.Fab")
			(hide yes)
			(effects
				(font
					(size 1 1)
					(thickness 0.15)
				)
			)
		)
		(property "Manufacturer" "Bourns"
			(at 100.371477 -84.634982 0)
			(layer "F.Fab")
			(hide yes)
			(effects
				(font
					(size 1 1)
					(thickness 0.15)
				)
			)
		)
		(property "Tolerance" "1%"
			(at 100.371477 -84.634982 0)
			(layer "F.Fab")
			(hide yes)
			(effects
				(font
					(size 1 1)
					(thickness 0.15)
				)
			)
		)
		(property "Val" "80k6"
			(at 100.371477 -84.634982 0)
			(layer "F.Fab")
			(hide yes)
			(effects
				(font
					(size 1 1)
					(thickness 0.15)
				)
			)
		)
		(sheetname "/Deserializer/")
		(sheetfile "deserializer.kicad_sch")
		(attr smd exclude_from_pos_files exclude_from_bom dnp)
		(fp_poly
			(pts
				(xy -0.925 -0.47) (xy 0.925 -0.47) (xy 0.925 0.47) (xy -0.925 0.47)
			)
			(stroke
				(width 0.05)
				(type default)
			)
			(fill no)
			(layer "F.CrtYd")
		)
		(fp_poly
			(pts
				(xy -0.5 -0.25) (xy 0.5 -0.25) (xy 0.5 0.25) (xy -0.5 0.25)
			)
			(stroke
				(width 0.15)
				(type solid)
			)
			(fill no)
			(layer "F.Fab")
		)
		(pad "1" smd roundrect
			(at -0.48 0 45)
			(size 0.59 0.64)
			(layers "F.Cu" "F.Mask" "F.Paste")
			(roundrect_rratio 0.25)
			(net 76 "/Deserializer/CFG0")
			(pintype "passive")
		)
		(pad "2" smd roundrect
			(at 0.48 0 45)
			(size 0.59 0.64)
			(layers "F.Cu" "F.Mask" "F.Paste")
			(roundrect_rratio 0.25)
			(net 146 "VDDIO")
			(pintype "passive")
		)
	)
	(footprint "antmicro-footprints:TSOT23-6"
		(layer "F.Cu")
		(at 134.773 94.602)
		(property "Reference" "U4"
			(at -1.042 2.553 180)
			(layer "F.SilkS")
			(effects
				(font
					(size 0.7 0.7)
					(thickness 0.15)
				)
				(justify left bottom)
			)
		)
		(property "Value" "AP62301_TSOT"
			(at 2.813 1.525 0)
			(layer "B.Fab")
			(effects
				(font
					(size 0.7 0.7)
					(thickness 0.15)
				)
				(justify left bottom mirror)
			)
		)
		(property "Datasheet" "https://www.diodes.com/assets/Datasheets/AP62300_AP62301_AP62300T.pdf"
			(at 0 0 0)
			(layer "F.Fab")
			(hide yes)
			(effects
				(font
					(size 1.27 1.27)
					(thickness 0.15)
				)
			)
		)
		(property "Description" "DC-DC Switching Synchronous Buck Regulator, Adjustable, 4.2V-18Vin, 0.8V-7V/3A out, TSOT-26-6"
			(at 0 0 0)
			(layer "F.Fab")
			(hide yes)
			(effects
				(font
					(size 1.27 1.27)
					(thickness 0.15)
				)
			)
		)
		(property "Author" "Antmicro"
			(at 0 0 0)
			(layer "F.Fab")
			(hide yes)
			(effects
				(font
					(size 1 1)
					(thickness 0.15)
				)
			)
		)
		(property "License" "Apache-2.0"
			(at 0 0 0)
			(layer "F.Fab")
			(hide yes)
			(effects
				(font
					(size 1 1)
					(thickness 0.15)
				)
			)
		)
		(property "MPN" "AP62301WU-7"
			(at 0 0 0)
			(layer "F.Fab")
			(hide yes)
			(effects
				(font
					(size 1 1)
					(thickness 0.15)
				)
			)
		)
		(property "Manufacturer" "Diodes Incorporated"
			(at 0 0 0)
			(layer "F.Fab")
			(hide yes)
			(effects
				(font
					(size 1 1)
					(thickness 0.15)
				)
			)
		)
		(sheetname "/Power/")
		(sheetfile "power.kicad_sch")
		(attr smd)
		(fp_line
			(start -1 -1.5)
			(end -1 -1.375)
			(stroke
				(width 0.15)
				(type solid)
			)
			(layer "F.SilkS")
		)
		(fp_line
			(start -1 1.55)
			(end -1 1.4)
			(stroke
				(width 0.15)
				(type solid)
			)
			(layer "F.SilkS")
		)
		(fp_line
			(start 1 -1.497)
			(end -1 -1.5)
			(stroke
				(width 0.15)
				(type solid)
			)
			(layer "F.SilkS")
		)
		(fp_line
			(start 1 -1.497)
			(end 1 -1.375)
			(stroke
				(width 0.15)
				(type solid)
			)
			(layer "F.SilkS")
		)
		(fp_line
			(start 1 1.55)
			(end -1 1.55)
			(stroke
				(width 0.15)
				(type solid)
			)
			(layer "F.SilkS")
		)
		(fp_line
			(start 1 1.55)
			(end 1 1.4)
			(stroke
				(width 0.15)
				(type solid)
			)
			(layer "F.SilkS")
		)
		(fp_circle
			(center -1.44 -1.5)
			(end -1.39 -1.5)
			(stroke
				(width 0.15)
				(type solid)
			)
			(fill yes)
			(layer "F.SilkS")
		)
		(fp_rect
			(start 1.93 -1.7)
			(end -1.93 1.7)
			(stroke
				(width 0.05)
				(type solid)
			)
			(fill no)
			(layer "F.CrtYd")
		)
		(fp_line
			(start -0.45 -1.521)
			(end -0.876 -1.096)
			(stroke
				(width 0.15)
				(type solid)
			)
			(layer "F.Fab")
		)
		(fp_rect
			(start 0.875 1.528)
			(end -0.875 -1.525)
			(stroke
				(width 0.15)
				(type solid)
			)
			(fill no)
			(layer "F.Fab")
		)
		(pad "1" smd rect
			(at -1.301 -0.947 270)
			(size 0.7 1.2)
			(layers "F.Cu" "F.Mask" "F.Paste")
			(net 1 "GND")
			(pinfunction "GND")
			(pintype "power_in")
		)
		(pad "2" smd rect
			(at -1.301 0.004 270)
			(size 0.7 1.2)
			(layers "F.Cu" "F.Mask" "F.Paste")
			(net 7 "/Power/SW_1V8")
			(pinfunction "SW")
			(pintype "power_out")
		)
		(pad "3" smd rect
			(at -1.301 0.954 270)
			(size 0.7 1.2)
			(layers "F.Cu" "F.Mask" "F.Paste")
			(net 4 "+12V")
			(pinfunction "VIN")
			(pintype "power_in")
		)
		(pad "4" smd rect
			(at 1.299 0.954 270)
			(size 0.7 1.2)
			(layers "F.Cu" "F.Mask" "F.Paste")
			(net 70 "/Power/FB_1V8")
			(pinfunction "FB")
			(pintype "input")
		)
		(pad "5" smd rect
			(at 1.299 0.004 270)
			(size 0.7 1.2)
			(layers "F.Cu" "F.Mask" "F.Paste")
			(net 69 "/Power/EN_1V8")
			(pinfunction "EN")
			(pintype "input")
		)
		(pad "6" smd rect
			(at 1.299 -0.947 270)
			(size 0.7 1.2)
			(layers "F.Cu" "F.Mask" "F.Paste")
			(net 6 "Net-(U4-BST)")
			(pinfunction "BST")
			(pintype "output")
		)
	)
	(footprint "antmicro-footprints:TP_SMD_0.75mm"
		(layer "F.Cu")
		(at 138.33 84.938)
		(property "Reference" "TP4"
			(at -3.3062 0.404 0)
			(layer "F.SilkS")
			(hide yes)
			(effects
				(font
					(size 0.7 0.7)
					(thickness 0.15)
				)
				(justify left bottom)
			)
		)
		(property "Value" "TP_0.75mm_SMD"
			(at 0 1.2 0)
			(layer "F.Fab")
			(effects
				(font
					(size 0.7 0.7)
					(thickness 0.15)
				)
				(justify left bottom)
			)
		)
		(property "Description" "SMT test point"
			(at 0 0 0)
			(layer "F.Fab")
			(hide yes)
			(effects
				(font
					(size 1.27 1.27)
					(thickness 0.15)
				)
			)
		)
		(property "Author" "Antmicro"
			(at 0 0 0)
			(layer "F.Fab")
			(hide yes)
			(effects
				(font
					(size 1 1)
					(thickness 0.15)
				)
			)
		)
		(property "License" "Apache-2.0"
			(at 0 0 0)
			(layer "F.Fab")
			(hide yes)
			(effects
				(font
					(size 1 1)
					(thickness 0.15)
				)
			)
		)
		(property "MPN" ""
			(at 0 0 0)
			(layer "F.Fab")
			(hide yes)
			(effects
				(font
					(size 1 1)
					(thickness 0.15)
				)
			)
		)
		(property "Manufacturer" ""
			(at 0 0 0)
			(layer "F.Fab")
			(hide yes)
			(effects
				(font
					(size 1 1)
					(thickness 0.15)
				)
			)
		)
		(sheetname "/Connectors/")
		(sheetfile "connectors.kicad_sch")
		(fp_circle
			(center 0 0)
			(end 0.475 0)
			(stroke
				(width 0.05)
				(type default)
			)
			(fill no)
			(layer "F.CrtYd")
		)
		(pad "1" smd circle
			(at 0 0)
			(size 0.75 0.75)
			(layers "F.Cu" "F.Mask")
			(net 87 "/Connectors/MFP8")
			(pinfunction "1")
			(pintype "passive")
		)
	)
	(footprint "antmicro-footprints:R_0402_1005Metric"
		(layer "F.Cu")
		(at 139.827 73.533 135)
		(descr "Resistor SMD 0402")
		(tags "resistor SMD 0402")
		(property "Reference" "R44"
			(at 6.254077 -0.468529 315)
			(unlocked yes)
			(layer "F.SilkS")
			(effects
				(font
					(size 0.7 0.7)
					(thickness 0.15)
				)
				(justify left bottom)
			)
		)
		(property "Value" "R_49R9_0402"
			(at -1.011843 1.772046 135)
			(layer "F.Fab")
			(effects
				(font
					(size 0.7 0.7)
					(thickness 0.15)
				)
				(justify left bottom)
			)
		)
		(property "Datasheet" "https://www.bourns.com/docs/product-datasheets/cr.pdf"
			(at 0 0 135)
			(layer "F.Fab")
			(hide yes)
			(effects
				(font
					(size 1.27 1.27)
					(thickness 0.15)
				)
			)
		)
		(property "Description" "SMD Chip Resistor, 49.9 ohm, ± 1%, 62.5 mW, 0402 [1005 Metric], Thick Film, General Purpose"
			(at 0 0 135)
			(layer "F.Fab")
			(hide yes)
			(effects
				(font
					(size 1.27 1.27)
					(thickness 0.15)
				)
			)
		)
		(property "Author" "Antmicro"
			(at 290.695303 26.656063 0)
			(layer "F.Fab")
			(hide yes)
			(effects
				(font
					(size 1 1)
					(thickness 0.15)
				)
			)
		)
		(property "License" "Apache-2.0"
			(at 290.695303 26.656063 0)
			(layer "F.Fab")
			(hide yes)
			(effects
				(font
					(size 1 1)
					(thickness 0.15)
				)
			)
		)
		(property "MPN" "CR0402-FX-49R9GLF"
			(at 290.695303 26.656063 0)
			(layer "F.Fab")
			(hide yes)
			(effects
				(font
					(size 1 1)
					(thickness 0.15)
				)
			)
		)
		(property "Manufacturer" "Bourns"
			(at 290.695303 26.656063 0)
			(layer "F.Fab")
			(hide yes)
			(effects
				(font
					(size 1 1)
					(thickness 0.15)
				)
			)
		)
		(property "Tolerance" "1%"
			(at 290.695303 26.656063 0)
			(layer "F.Fab")
			(hide yes)
			(effects
				(font
					(size 1 1)
					(thickness 0.15)
				)
			)
		)
		(property "Val" "49R9"
			(at 290.695303 26.656063 0)
			(layer "F.Fab")
			(hide yes)
			(effects
				(font
					(size 1 1)
					(thickness 0.15)
				)
			)
		)
		(sheetname "/Deserializer/")
		(sheetfile "deserializer.kicad_sch")
		(attr smd)
		(fp_poly
			(pts
				(xy -0.925 -0.47) (xy 0.925 -0.47) (xy 0.925 0.47) (xy -0.925 0.47)
			)
			(stroke
				(width 0.05)
				(type default)
			)
			(fill no)
			(layer "F.CrtYd")
		)
		(fp_poly
			(pts
				(xy -0.5 -0.25) (xy 0.5 -0.25) (xy 0.5 0.25) (xy -0.5 0.25)
			)
			(stroke
				(width 0.15)
				(type solid)
			)
			(fill no)
			(layer "F.Fab")
		)
		(pad "1" smd roundrect
			(at -0.48 0 135)
			(size 0.59 0.64)
			(layers "F.Cu" "F.Mask" "F.Paste")
			(roundrect_rratio 0.25)
			(net 21 "Net-(C33-Pad2)")
			(pintype "passive")
		)
		(pad "2" smd roundrect
			(at 0.48 0 135)
			(size 0.59 0.64)
			(layers "F.Cu" "F.Mask" "F.Paste")
			(roundrect_rratio 0.25)
			(net 1 "GND")
			(pintype "passive")
		)
	)
)
